(kicad_pcb
	(version 20260206)
	(generator "pcbnew")
	(generator_version "10.0")
	(general
		(thickness 1.6)
		(legacy_teardrops no)
	)
	(paper "A4")
	(title_block
		(title "timecard-production-celestica-r4006 — R4006-B0001-02_R01.brd")
		(comment 1 "Time Appliance Project (Time Card) / footprints 803-807 of 1113")
	)
	(layers
		(0 "F.Cu" signal "TOP")
		(4 "In1.Cu" signal "L02_GND1")
		(6 "In2.Cu" signal "L03_SIG1")
		(8 "In3.Cu" signal "L04_GND2")
		(10 "In4.Cu" signal "L05_VCC1")
		(12 "In5.Cu" signal "L06_VCC2")
		(14 "In6.Cu" signal "L07_GND3")
		(16 "In7.Cu" signal "L08_SIG2")
		(18 "In8.Cu" signal "L09_GND4")
		(2 "B.Cu" signal "BOTTOM")
		(9 "F.Adhes" user "F.Adhesive")
		(11 "B.Adhes" user "B.Adhesive")
		(13 "F.Paste" user "Package Geometry/Pastemask Top")
		(15 "B.Paste" user "Package Geometry/Pastemask Bottom")
		(5 "F.SilkS" user "Ref Des/Silkscreen Top")
		(7 "B.SilkS" user "Ref Des/Silkscreen Bottom")
		(1 "F.Mask" user "Board Geometry/Soldermask Top")
		(3 "B.Mask" user "Board Geometry/Soldermask Bottom")
		(17 "Dwgs.User" user "User.Drawings")
		(19 "Cmts.User" user "User.Comments")
		(21 "Eco1.User" user "User.Eco1")
		(23 "Eco2.User" user "User.Eco2")
		(25 "Edge.Cuts" user "Board Geometry/Outline")
		(27 "Margin" user)
		(31 "F.CrtYd" user "Package Geometry/Place Bound Top")
		(29 "B.CrtYd" user "Package Geometry/Place Bound Bottom")
		(35 "F.Fab" user "Ref Des/Assembly Top")
		(33 "B.Fab" user "Ref Des/Assembly Bottom")
	)
	(footprint ""
		(layer "B.Cu")
		(at 151.892 -36.576 90)
		(property "Reference" "R431"
			(at -4.99237 0.635 0)
			(unlocked yes)
			(layer "B.SilkS")
			(effects
				(font
					(size 0.7874 0.5842)
					(thickness 0.1524)
				)
				(justify mirror)
			)
		)
		(property "Value" "VAL*"
			(at -0.02032 2.13233 90)
			(unlocked yes)
			(layer "B.Fab")
			(hide yes)
			(effects
				(font
					(size 0.7874 0.5842)
					(thickness 0.1524)
				)
				(justify mirror)
			)
		)
		(property "Tolerance" "TOL*"
			(at -0.044704 3.05435 90)
			(unlocked yes)
			(layer "Cmts.User")
			(hide yes)
			(effects
				(font
					(size 0.7874 0.5842)
					(thickness 0.1524)
				)
				(justify mirror)
			)
		)
		(property "User Part Number" "PARTNUM*"
			(at -0.02032 4.024884 90)
			(unlocked yes)
			(layer "Cmts.User")
			(hide yes)
			(effects
				(font
					(size 0.7874 0.5842)
					(thickness 0.1524)
				)
				(justify mirror)
			)
		)
		(property "Device Type" "RESISTOR-G155-133R0-01,33OHM,1%"
			(at -0.008382 1.210564 90)
			(unlocked yes)
			(layer "B.Fab")
			(hide yes)
			(effects
				(font
					(size 0.7874 0.5842)
					(thickness 0.1524)
				)
				(justify mirror)
			)
		)
		(duplicate_pad_numbers_are_jumpers no)
		(fp_line
			(start 1.143 -0.5588)
			(end 1.143 0.5588)
			(stroke
				(width 0.1)
				(type default)
			)
			(layer "B.SilkS")
		)
		(fp_line
			(start -1.143 -0.5588)
			(end 1.143 -0.5588)
			(stroke
				(width 0.1)
				(type default)
			)
			(layer "B.SilkS")
		)
		(fp_line
			(start 1.143 0.5588)
			(end -1.143 0.5588)
			(stroke
				(width 0.1)
				(type default)
			)
			(layer "B.SilkS")
		)
		(fp_line
			(start -1.143 0.5588)
			(end -1.143 -0.5588)
			(stroke
				(width 0.1)
				(type default)
			)
			(layer "B.SilkS")
		)
		(fp_poly
			(pts
				(xy 1.143 0.5588) (xy -1.143 0.5588) (xy -1.143 -0.5588) (xy 1.143 -0.5588)
			)
			(stroke
				(width 0)
				(type default)
			)
			(fill no)
			(layer "B.CrtYd")
		)
		(fp_line
			(start 0.508 -0.3048)
			(end 0.508 0.3048)
			(stroke
				(width 0.1)
				(type default)
			)
			(layer "B.Fab")
		)
		(fp_line
			(start -0.508 -0.3048)
			(end 0.508 -0.3048)
			(stroke
				(width 0.1)
				(type default)
			)
			(layer "B.Fab")
		)
		(fp_line
			(start 0.508 0.3048)
			(end -0.508 0.3048)
			(stroke
				(width 0.1)
				(type default)
			)
			(layer "B.Fab")
		)
		(fp_line
			(start -0.508 0.3048)
			(end -0.508 -0.3048)
			(stroke
				(width 0.1)
				(type default)
			)
			(layer "B.Fab")
		)
		(pad "1" smd rect
			(at 0.5334 0 270)
			(size 0.7112 0.6096)
			(layers "B.Cu" "B.Mask" "B.Paste")
			(net "UNNAMED_16_CONNHDR2X6FSSMT_I1_5")
		)
		(pad "2" smd rect
			(at -0.5334 0 270)
			(size 0.7112 0.6096)
			(layers "B.Cu" "B.Mask" "B.Paste")
			(net "FPGA_IO_3")
		)
		(zone
			(layer "B.Cu")
			(hatch none 0.5)
			(connect_pads
				(clearance 0)
			)
			(min_thickness 0.25)
			(keepout
				(tracks allowed)
				(vias not_allowed)
				(pads allowed)
				(copperpour not_allowed)
				(footprints allowed)
			)
			(placement
				(enabled no)
				(sheetname "")
			)
			(fill
				(thermal_gap 0.5)
				(thermal_bridge_width 0.5)
				(island_removal_mode 0)
			)
			(polygon
				(pts
					(xy 152.1968 -36.6522) (xy 151.5872 -36.6522) (xy 151.5872 -36.4998) (xy 152.1968 -36.4998)
				)
			)
		)
		(zone
			(layer "B.Cu")
			(hatch none 0.5)
			(connect_pads
				(clearance 0)
			)
			(min_thickness 0.25)
			(keepout
				(tracks not_allowed)
				(vias allowed)
				(pads allowed)
				(copperpour not_allowed)
				(footprints allowed)
			)
			(placement
				(enabled no)
				(sheetname "")
			)
			(fill
				(thermal_gap 0.5)
				(thermal_bridge_width 0.5)
				(island_removal_mode 0)
			)
			(polygon
				(pts
					(xy 152.1968 -36.6522) (xy 151.5872 -36.6522) (xy 151.5872 -36.4998) (xy 152.1968 -36.4998)
				)
			)
		)
	)
	(footprint ""
		(layer "B.Cu")
		(at 72.517 -72.771 -90)
		(property "Reference" "C59"
			(at -3.81 -0.59563 270)
			(unlocked yes)
			(layer "B.SilkS")
			(effects
				(font
					(size 0.7874 0.5842)
					(thickness 0.1524)
				)
				(justify mirror)
			)
		)
		(property "Value" "VAL*"
			(at -0.0762 2.067306 270)
			(unlocked yes)
			(layer "B.Fab")
			(hide yes)
			(effects
				(font
					(size 0.7874 0.5842)
					(thickness 0.1524)
				)
				(justify mirror)
			)
		)
		(property "Tolerance" "TOL*"
			(at -0.0762 3.032506 270)
			(unlocked yes)
			(layer "Cmts.User")
			(hide yes)
			(effects
				(font
					(size 0.7874 0.5842)
					(thickness 0.1524)
				)
				(justify mirror)
			)
		)
		(property "User Part Number" "PARTNUM*"
			(at -0.1016 4.023106 270)
			(unlocked yes)
			(layer "Cmts.User")
			(hide yes)
			(effects
				(font
					(size 0.7874 0.5842)
					(thickness 0.1524)
				)
				(justify mirror)
			)
		)
		(property "Device Type" "CAPACITOR-G105-0B104-EK,0.1UF,A"
			(at -0.0508 1.127506 270)
			(unlocked yes)
			(layer "B.Fab")
			(hide yes)
			(effects
				(font
					(size 0.7874 0.5842)
					(thickness 0.1524)
				)
				(justify mirror)
			)
		)
		(duplicate_pad_numbers_are_jumpers no)
		(fp_line
			(start -1.143 0.5588)
			(end -1.143 -0.5588)
			(stroke
				(width 0.1)
				(type default)
			)
			(layer "B.SilkS")
		)
		(fp_line
			(start 1.143 0.5588)
			(end -1.143 0.5588)
			(stroke
				(width 0.1)
				(type default)
			)
			(layer "B.SilkS")
		)
		(fp_line
			(start -1.143 -0.5588)
			(end 1.143 -0.5588)
			(stroke
				(width 0.1)
				(type default)
			)
			(layer "B.SilkS")
		)
		(fp_line
			(start 1.143 -0.5588)
			(end 1.143 0.5588)
			(stroke
				(width 0.1)
				(type default)
			)
			(layer "B.SilkS")
		)
		(fp_rect
			(start 1.143 -0.5588)
			(end -1.143 0.5588)
			(stroke
				(width 0)
				(type default)
			)
			(fill no)
			(layer "B.CrtYd")
		)
		(fp_line
			(start -0.508 0.3048)
			(end -0.508 -0.3048)
			(stroke
				(width 0.1)
				(type default)
			)
			(layer "B.Fab")
		)
		(fp_line
			(start 0.508 0.3048)
			(end -0.508 0.3048)
			(stroke
				(width 0.1)
				(type default)
			)
			(layer "B.Fab")
		)
		(fp_line
			(start -0.508 -0.3048)
			(end 0.508 -0.3048)
			(stroke
				(width 0.1)
				(type default)
			)
			(layer "B.Fab")
		)
		(fp_line
			(start 0.508 -0.3048)
			(end 0.508 0.3048)
			(stroke
				(width 0.1)
				(type default)
			)
			(layer "B.Fab")
		)
		(pad "1" smd rect
			(at 0.5334 0 90)
			(size 0.7112 0.6096)
			(layers "B.Cu" "B.Mask" "B.Paste")
			(net "XP5R0V_MAC")
		)
		(pad "2" smd rect
			(at -0.5334 0 90)
			(size 0.7112 0.6096)
			(layers "B.Cu" "B.Mask" "B.Paste")
			(net "SG")
		)
		(zone
			(layer "B.Cu")
			(hatch none 0.5)
			(connect_pads
				(clearance 0)
			)
			(min_thickness 0.25)
			(keepout
				(tracks allowed)
				(vias not_allowed)
				(pads allowed)
				(copperpour not_allowed)
				(footprints allowed)
			)
			(placement
				(enabled no)
				(sheetname "")
			)
			(fill
				(thermal_gap 0.5)
				(thermal_bridge_width 0.5)
				(island_removal_mode 0)
			)
			(polygon
				(pts
					(xy 72.8218 -72.6948) (xy 72.8218 -72.8472) (xy 72.2122 -72.8472) (xy 72.2122 -72.6948)
				)
			)
		)
	)
	(footprint ""
		(layer "B.Cu")
		(at 80.899 -73.152 -90)
		(property "Reference" "L3"
			(at -2.3622 0.29337 270)
			(unlocked yes)
			(layer "B.SilkS")
			(effects
				(font
					(size 0.7874 0.5842)
					(thickness 0.1524)
				)
				(justify left mirror)
			)
		)
		(property "Value" "VAL*"
			(at 0.9398 3.70967 270)
			(unlocked yes)
			(layer "B.Fab")
			(hide yes)
			(effects
				(font
					(size 0.7874 0.5842)
					(thickness 0.1524)
				)
				(justify left mirror)
			)
		)
		(property "Tolerance" "TOL*"
			(at 0.9906 5.00507 270)
			(unlocked yes)
			(layer "Cmts.User")
			(hide yes)
			(effects
				(font
					(size 0.7874 0.5842)
					(thickness 0.1524)
				)
				(justify left mirror)
			)
		)
		(property "User Part Number" "PARTNUM*"
			(at 2.54 2.46507 270)
			(unlocked yes)
			(layer "Cmts.User")
			(hide yes)
			(effects
				(font
					(size 0.7874 0.5842)
					(thickness 0.1524)
				)
				(justify left mirror)
			)
		)
		(property "Device Type" "FERRITEBEAD-G191-10101-01,26OHA"
			(at 0.9906 1.22047 270)
			(unlocked yes)
			(layer "B.Fab")
			(hide yes)
			(effects
				(font
					(size 0.7874 0.5842)
					(thickness 0.1524)
				)
				(justify left mirror)
			)
		)
		(duplicate_pad_numbers_are_jumpers no)
		(fp_line
			(start -1.3208 0.7112)
			(end 1.3208 0.7112)
			(stroke
				(width 0.1)
				(type default)
			)
			(layer "B.SilkS")
		)
		(fp_line
			(start 1.3208 0.7112)
			(end 1.3208 -0.7112)
			(stroke
				(width 0.1)
				(type default)
			)
			(layer "B.SilkS")
		)
		(fp_line
			(start -1.3208 -0.7112)
			(end -1.3208 0.7112)
			(stroke
				(width 0.1)
				(type default)
			)
			(layer "B.SilkS")
		)
		(fp_line
			(start 1.3208 -0.7112)
			(end -1.3208 -0.7112)
			(stroke
				(width 0.1)
				(type default)
			)
			(layer "B.SilkS")
		)
		(fp_rect
			(start 1.3208 0.7112)
			(end -1.3208 -0.7112)
			(stroke
				(width 0)
				(type default)
			)
			(fill no)
			(layer "B.CrtYd")
		)
		(fp_line
			(start -0.8128 0.4572)
			(end 0.8128 0.4572)
			(stroke
				(width 0.1)
				(type default)
			)
			(layer "B.Fab")
		)
		(fp_line
			(start 0.8128 0.4572)
			(end 0.8128 -0.4572)
			(stroke
				(width 0.1)
				(type default)
			)
			(layer "B.Fab")
		)
		(fp_line
			(start -0.8128 -0.4572)
			(end -0.8128 0.4572)
			(stroke
				(width 0.1)
				(type default)
			)
			(layer "B.Fab")
		)
		(fp_line
			(start 0.8128 -0.4572)
			(end -0.8128 -0.4572)
			(stroke
				(width 0.1)
				(type default)
			)
			(layer "B.Fab")
		)
		(pad "1" smd rect
			(at 0.6858 0 90)
			(size 0.762 0.8636)
			(layers "B.Cu" "B.Mask" "B.Paste")
			(net "XP5R0V_MAC")
		)
		(pad "2" smd rect
			(at -0.6858 0 90)
			(size 0.762 0.8636)
			(layers "B.Cu" "B.Mask" "B.Paste")
			(net "XP5R0V")
		)
		(zone
			(layer "B.Cu")
			(hatch none 0.5)
			(connect_pads
				(clearance 0)
			)
			(min_thickness 0.25)
			(keepout
				(tracks not_allowed)
				(vias allowed)
				(pads allowed)
				(copperpour not_allowed)
				(footprints allowed)
			)
			(placement
				(enabled no)
				(sheetname "")
			)
			(fill
				(thermal_gap 0.5)
				(thermal_bridge_width 0.5)
				(island_removal_mode 0)
			)
			(polygon
				(pts
					(xy 80.4418 -72.9996) (xy 81.3562 -72.9996) (xy 81.3562 -73.3044) (xy 80.4418 -73.3044)
				)
			)
		)
		(zone
			(layer "B.Cu")
			(hatch none 0.5)
			(connect_pads
				(clearance 0)
			)
			(min_thickness 0.25)
			(keepout
				(tracks allowed)
				(vias not_allowed)
				(pads allowed)
				(copperpour not_allowed)
				(footprints allowed)
			)
			(placement
				(enabled no)
				(sheetname "")
			)
			(fill
				(thermal_gap 0.5)
				(thermal_bridge_width 0.5)
				(island_removal_mode 0)
			)
			(polygon
				(pts
					(xy 80.4418 -72.9996) (xy 81.3562 -72.9996) (xy 81.3562 -73.3044) (xy 80.4418 -73.3044)
				)
			)
		)
	)
	(footprint ""
		(layer "B.Cu")
		(at 104.34701 -49.823116)
		(property "Reference" "C153"
			(at -0.20701 -0.945134 0)
			(unlocked yes)
			(layer "B.SilkS")
			(effects
				(font
					(size 0.635 0.4064)
					(thickness 0.1524)
				)
				(justify mirror)
			)
		)
		(property "Value" "VAL*"
			(at 0 3.718306 0)
			(unlocked yes)
			(layer "B.Fab")
			(hide yes)
			(effects
				(font
					(size 0.7874 0.5842)
					(thickness 0.127)
				)
				(justify mirror)
			)
		)
		(property "Device Type" "CAPACITOR-G105-0B104-CK,0.1UF,A"
			(at 0 1.432306 0)
			(unlocked yes)
			(layer "B.Fab")
			(hide yes)
			(effects
				(font
					(size 0.7874 0.5842)
					(thickness 0.127)
				)
				(justify mirror)
			)
		)
		(property "User Part Number" "PARTNUM*"
			(at 0 2.575306 0)
			(unlocked yes)
			(layer "Cmts.User")
			(hide yes)
			(effects
				(font
					(size 0.7874 0.5842)
					(thickness 0.127)
				)
				(justify mirror)
			)
		)
		(property "Tolerance" "TOL*"
			(at 0 4.861306 0)
			(unlocked yes)
			(layer "Cmts.User")
			(hide yes)
			(effects
				(font
					(size 0.7874 0.5842)
					(thickness 0.127)
				)
				(justify mirror)
			)
		)
		(duplicate_pad_numbers_are_jumpers no)
		(fp_line
			(start -0.970026 -0.4699)
			(end -0.970026 0.4699)
			(stroke
				(width 0.1)
				(type default)
			)
			(layer "B.SilkS")
		)
		(fp_line
			(start -0.970026 0.4699)
			(end 0.970026 0.4699)
			(stroke
				(width 0.1)
				(type default)
			)
			(layer "B.SilkS")
		)
		(fp_line
			(start 0.970026 -0.4699)
			(end -0.970026 -0.4699)
			(stroke
				(width 0.1)
				(type default)
			)
			(layer "B.SilkS")
		)
		(fp_line
			(start 0.970026 0.4699)
			(end 0.970026 -0.4699)
			(stroke
				(width 0.1)
				(type default)
			)
			(layer "B.SilkS")
		)
		(fp_poly
			(pts
				(xy 0.970026 0.4699) (xy -0.970026 0.4699) (xy -0.970026 -0.4699) (xy 0.970026 -0.4699)
			)
			(stroke
				(width 0)
				(type default)
			)
			(fill no)
			(layer "B.CrtYd")
		)
		(fp_line
			(start -0.508 -0.3048)
			(end -0.508 0.3048)
			(stroke
				(width 0.1)
				(type default)
			)
			(layer "B.Fab")
		)
		(fp_line
			(start -0.508 0.3048)
			(end 0.508 0.3048)
			(stroke
				(width 0.1)
				(type default)
			)
			(layer "B.Fab")
		)
		(fp_line
			(start 0.508 -0.3048)
			(end -0.508 -0.3048)
			(stroke
				(width 0.1)
				(type default)
			)
			(layer "B.Fab")
		)
		(fp_line
			(start 0.508 0.3048)
			(end 0.508 -0.3048)
			(stroke
				(width 0.1)
				(type default)
			)
			(layer "B.Fab")
		)
		(pad "1" smd circle
			(at 0.500126 0 180)
			(size 0.635 0.635)
			(layers "B.Cu" "B.Mask" "B.Paste")
			(net "XP3R3V_FPGA")
		)
		(pad "2" smd circle
			(at -0.500126 0 180)
			(size 0.635 0.635)
			(layers "B.Cu" "B.Mask" "B.Paste")
			(net "SG")
		)
	)
	(footprint ""
		(layer "B.Cu")
		(at 109.22 -51.0032 -90)
		(property "Reference" "C149"
			(at -0.9398 -0.98425 270)
			(unlocked yes)
			(layer "B.SilkS")
			(effects
				(font
					(size 0.635 0.4064)
					(thickness 0.1524)
				)
				(justify mirror)
			)
		)
		(property "Value" "VAL*"
			(at -0.0762 2.067306 270)
			(unlocked yes)
			(layer "B.Fab")
			(hide yes)
			(effects
				(font
					(size 0.7874 0.5842)
					(thickness 0.1524)
				)
				(justify mirror)
			)
		)
		(property "Device Type" "CAPACITOR-G105-0B104-CK,0.1UF,A"
			(at -0.0508 1.127506 270)
			(unlocked yes)
			(layer "B.Fab")
			(hide yes)
			(effects
				(font
					(size 0.7874 0.5842)
					(thickness 0.1524)
				)
				(justify mirror)
			)
		)
		(property "User Part Number" "PARTNUM*"
			(at -0.1016 4.023106 270)
			(unlocked yes)
			(layer "Cmts.User")
			(hide yes)
			(effects
				(font
					(size 0.7874 0.5842)
					(thickness 0.1524)
				)
				(justify mirror)
			)
		)
		(property "Tolerance" "TOL*"
			(at -0.0762 3.032506 270)
			(unlocked yes)
			(layer "Cmts.User")
			(hide yes)
			(effects
				(font
					(size 0.7874 0.5842)
					(thickness 0.1524)
				)
				(justify mirror)
			)
		)
		(duplicate_pad_numbers_are_jumpers no)
		(fp_line
			(start -1.143 0.5588)
			(end -1.143 -0.5588)
			(stroke
				(width 0.1)
				(type default)
			)
			(layer "B.SilkS")
		)
		(fp_line
			(start 1.143 0.5588)
			(end -1.143 0.5588)
			(stroke
				(width 0.1)
				(type default)
			)
			(layer "B.SilkS")
		)
		(fp_line
			(start -1.143 -0.5588)
			(end 1.143 -0.5588)
			(stroke
				(width 0.1)
				(type default)
			)
			(layer "B.SilkS")
		)
		(fp_line
			(start 1.143 -0.5588)
			(end 1.143 0.5588)
			(stroke
				(width 0.1)
				(type default)
			)
			(layer "B.SilkS")
		)
		(fp_rect
			(start 1.143 0.5588)
			(end -1.143 -0.5588)
			(stroke
				(width 0)
				(type default)
			)
			(fill no)
			(layer "B.CrtYd")
		)
		(fp_line
			(start -0.508 0.3048)
			(end -0.508 -0.3048)
			(stroke
				(width 0.1)
				(type default)
			)
			(layer "B.Fab")
		)
		(fp_line
			(start 0.508 0.3048)
			(end -0.508 0.3048)
			(stroke
				(width 0.1)
				(type default)
			)
			(layer "B.Fab")
		)
		(fp_line
			(start -0.508 -0.3048)
			(end 0.508 -0.3048)
			(stroke
				(width 0.1)
				(type default)
			)
			(layer "B.Fab")
		)
		(fp_line
			(start 0.508 -0.3048)
			(end 0.508 0.3048)
			(stroke
				(width 0.1)
				(type default)
			)
			(layer "B.Fab")
		)
		(pad "1" smd rect
			(at 0.5334 0 90)
			(size 0.7112 0.6096)
			(layers "B.Cu" "B.Mask" "B.Paste")
			(net "XP3R3V_FPGA")
		)
		(pad "2" smd rect
			(at -0.5334 0 90)
			(size 0.7112 0.6096)
			(layers "B.Cu" "B.Mask" "B.Paste")
			(net "SG")
		)
		(zone
			(layer "B.Cu")
			(hatch none 0.5)
			(connect_pads
				(clearance 0)
			)
			(min_thickness 0.25)
			(keepout
				(tracks allowed)
				(vias not_allowed)
				(pads allowed)
				(copperpour not_allowed)
				(footprints allowed)
			)
			(placement
				(enabled no)
				(sheetname "")
			)
			(fill
				(thermal_gap 0.5)
				(thermal_bridge_width 0.5)
				(island_removal_mode 0)
			)
			(polygon
				(pts
					(xy 108.9152 -50.927) (xy 109.5248 -50.927) (xy 109.5248 -51.0794) (xy 108.9152 -51.0794)
				)
			)
		)
	)
)
